# S9S_MB_2U (Grand Teton) — schematic netlist excerpt (pin names and nets, part order shuffled) for the footprints in the layout excerpt that follows; sources: Cadence DE-HDL packaged netlist, KiCad conversion of 03242023_DA0F0TMBIJ0_F0T_Motherboard_J_brd_V01_OCP.brd

J109  CONN112_10137002101LF  CONN112_10137002-101LF IO  pkg HSD_F112D8_P2W1-2_RDH  page 140
  A1  = BMC_MONITER_BUF
  A2  = GND
  A3  = BIC_MONITER
  A4  = GND
  A5  = SMB_BMC_SWB_BUF_SCL
  A6  = GND
  A7  = SMB_BMC_SWB_BUF_SDA
  A8  = GND
  B1  = GND
  B2  = P5E_CPU1_PE3_RX_DP<6>
  B3  = GND
  B4  = P5E_CPU1_PE3_RX_DP<4>
  B5  = GND
  B6  = P5E_CPU1_PE3_RX_DN<2>
  B7  = GND
  B8  = P5E_CPU1_PE3_RX_DP<0>
  C1  = P5E_CPU1_PE3_RX_DP<7>
  C2  = P5E_CPU1_PE3_RX_DN<6>
  C3  = P5E_CPU1_PE3_RX_DP<5>
  C4  = P5E_CPU1_PE3_RX_DN<4>
  C5  = P5E_CPU1_PE3_RX_DN<3>
  C6  = P5E_CPU1_PE3_RX_DP<2>
  C7  = P5E_CPU1_PE3_RX_DN<1>
  C8  = P5E_CPU1_PE3_RX_DN<0>
  D1  = P5E_CPU1_PE3_RX_DN<7>
  D2  = GND
  D3  = P5E_CPU1_PE3_RX_DN<5>
  D4  = GND
  D5  = P5E_CPU1_PE3_RX_DP<3>
  D6  = GND
  D7  = P5E_CPU1_PE3_RX_DP<1>
  D8  = GND
  E1  = GND
  E2  = P5E_CPU1_PE2_RX_DP<6>
  E3  = GND
  E4  = P5E_CPU1_PE2_RX_DP<4>
  E5  = GND
  E6  = P5E_CPU1_PE2_RX_DP<2>
  E7  = GND
  E8  = P5E_CPU1_PE2_RX_DP<0>
  F1  = P5E_CPU1_PE2_RX_DP<7>
  F2  = P5E_CPU1_PE2_RX_DN<6>
  F3  = P5E_CPU1_PE2_RX_DP<5>
  F4  = P5E_CPU1_PE2_RX_DN<4>
  F5  = P5E_CPU1_PE2_RX_DP<3>
  F6  = P5E_CPU1_PE2_RX_DN<2>
  F7  = P5E_CPU1_PE2_RX_DP<1>
  F8  = P5E_CPU1_PE2_RX_DN<0>
  G1  = P5E_CPU1_PE2_RX_DN<7>
  G2  = GND
  G3  = P5E_CPU1_PE2_RX_DN<5>
  G4  = GND
  G5  = P5E_CPU1_PE2_RX_DN<3>
  G6  = GND
  G7  = P5E_CPU1_PE2_RX_DN<1>
  G8  = GND
  H1  = GND
  H2  = P5E_CPU1_PE3_TX_C_DN<6>
  H3  = GND
  H4  = P5E_CPU1_PE3_TX_C_DN<4>
  H5  = GND
  H6  = P5E_CPU1_PE3_TX_C_DN<2>
  H7  = GND
  H8  = P5E_CPU1_PE3_TX_C_DP<0>
  I1  = P5E_CPU1_PE3_TX_C_DN<7>
  I2  = P5E_CPU1_PE3_TX_C_DP<6>
  I3  = P5E_CPU1_PE3_TX_C_DN<5>
  I4  = P5E_CPU1_PE3_TX_C_DP<4>
  I5  = P5E_CPU1_PE3_TX_C_DN<3>
  I6  = P5E_CPU1_PE3_TX_C_DP<2>
  I7  = P5E_CPU1_PE3_TX_C_DN<1>
  I8  = P5E_CPU1_PE3_TX_C_DN<0>
  J1  = P5E_CPU1_PE3_TX_C_DP<7>
  J2  = GND
  J3  = P5E_CPU1_PE3_TX_C_DP<5>
  J4  = GND
  J5  = P5E_CPU1_PE3_TX_C_DP<3>
  J6  = GND
  J7  = P5E_CPU1_PE3_TX_C_DP<1>
  J8  = GND
  K1  = GND
  K2  = P5E_CPU1_PE2_TX_C_DP<6>
  K3  = GND
  K4  = P5E_CPU1_PE2_TX_C_DP<4>
  K5  = GND
  K6  = P5E_CPU1_PE2_TX_C_DP<2>
  K7  = GND
  K8  = P5E_CPU1_PE2_TX_C_DP<0>
  L1  = P5E_CPU1_PE2_TX_C_DP<7>
  L2  = P5E_CPU1_PE2_TX_C_DN<6>
  L3  = P5E_CPU1_PE2_TX_C_DP<5>
  L4  = P5E_CPU1_PE2_TX_C_DN<4>
  L5  = P5E_CPU1_PE2_TX_C_DP<3>
  L6  = P5E_CPU1_PE2_TX_C_DN<2>
  L7  = P5E_CPU1_PE2_TX_C_DP<1>
  L8  = P5E_CPU1_PE2_TX_C_DN<0>
  M1  = P5E_CPU1_PE2_TX_C_DN<7>
  M2  = GND
  M3  = P5E_CPU1_PE2_TX_C_DN<5>
  M4  = GND
  M5  = P5E_CPU1_PE2_TX_C_DN<3>
  M6  = GND
  M7  = P5E_CPU1_PE2_TX_C_DN<1>
  M8  = GND
  N1  = GND
  N2  = GPU_FPGA_EROT_FATALERR_N
  N3  = GND
  N4  = GPU_3V3IO_RSVD0_FFU
  N5  = GND
  N6  = GPU_3V3IO_RSVD1_FFU
  N7  = GND
  N8  = PRSNT_CABLE_GPU_B3_N

(kicad_pcb
	(version 20260206)
	(generator "pcbnew")
	(generator_version "10.0")
	(general
		(thickness 1.6)
		(legacy_teardrops no)
	)
	(paper "A4")
	(title_block
		(title "03242023_DA0F0TMBIJ0_F0T_Motherboard_J_brd_V01_OCP.brd")
		(comment 1 "Grand Teton / footprint 3035 of 6105 (J109), pads 32-48 of 48")
	)
	(layers
		(0 "F.Cu" signal "TOP")
		(4 "In1.Cu" signal "GND")
		(6 "In2.Cu" signal "IN1")
		(8 "In3.Cu" signal "GND1")
		(10 "In4.Cu" signal "IN2")
		(12 "In5.Cu" signal "GND2")
		(14 "In6.Cu" signal "IN3")
		(16 "In7.Cu" signal "GND3")
		(18 "In8.Cu" signal "VCC")
		(20 "In9.Cu" signal "VCC1")
		(22 "In10.Cu" signal "GND4")
		(24 "In11.Cu" signal "IN4")
		(26 "In12.Cu" signal "GND5")
		(28 "In13.Cu" signal "IN5")
		(30 "In14.Cu" signal "GND6")
		(32 "In15.Cu" signal "IN6")
		(34 "In16.Cu" signal "GND7")
		(2 "B.Cu" signal "BOTTOM")
		(9 "F.Adhes" user "F.Adhesive")
		(11 "B.Adhes" user "B.Adhesive")
		(13 "F.Paste" user "Package Geometry/Pastemask Top")
		(15 "B.Paste" user "Package Geometry/Pastemask Bottom")
		(5 "F.SilkS" user "Ref Des/Silkscreen Top")
		(7 "B.SilkS" user "Ref Des/Silkscreen Bottom")
		(1 "F.Mask" user "Board Geometry/Soldermask Top")
		(3 "B.Mask" user "Board Geometry/Soldermask Bottom")
		(17 "Dwgs.User" user "User.Drawings")
		(19 "Cmts.User" user "User.Comments")
		(21 "Eco1.User" user "User.Eco1")
		(23 "Eco2.User" user "User.Eco2")
		(25 "Edge.Cuts" user "Board Geometry/Outline")
		(27 "Margin" user)
		(31 "F.CrtYd" user "Package Geometry/Place Bound Top")
		(29 "B.CrtYd" user "Package Geometry/Place Bound Bottom")
		(35 "F.Fab" user "Ref Des/Assembly Top")
		(33 "B.Fab" user "Ref Des/Assembly Bottom")
	)
	(footprint ""
		(layer "F.Cu")
		(at 142.750032 -440.489848)
		(property "Reference" "J109"
			(at 1.4859 23.131272 0)
			(unlocked yes)
			(layer "F.SilkS")
			(effects
				(font
					(size 0.7874 0.5842)
					(thickness 0.1524)
				)
				(justify left)
			)
		)
		(property "Value" ""
			(at 0 0 0)
			(layer "F.Fab")
			(effects
				(font
					(size 1.27 1.27)
				)
			)
		)
		(duplicate_pad_numbers_are_jumpers no)
		(pad "J8" thru_hole circle
			(at 13.999972 10.999978 180)
			(size 0.906272 0.906272)
			(drill 0.499872)
			(layers "*.Cu" "*.Mask")
			(remove_unused_layers no)
			(net "GND")
			(clearance 0.0508)
			(thermal_gap 0.0508)
		)
		(pad "K1" thru_hole circle
			(at 0 11.999976 180)
			(size 0.906272 0.906272)
			(drill 0.499872)
			(layers "*.Cu" "*.Mask")
			(remove_unused_layers no)
			(net "GND")
			(clearance 0.0508)
			(thermal_gap 0.0508)
		)
		(pad "K3" thru_hole circle
			(at 3.999992 11.999976 180)
			(size 0.906272 0.906272)
			(drill 0.499872)
			(layers "*.Cu" "*.Mask")
			(remove_unused_layers no)
			(net "GND")
			(clearance 0.0508)
			(thermal_gap 0.0508)
		)
		(pad "K5" thru_hole circle
			(at 7.999984 11.999976 180)
			(size 0.906272 0.906272)
			(drill 0.499872)
			(layers "*.Cu" "*.Mask")
			(remove_unused_layers no)
			(net "GND")
			(clearance 0.0508)
			(thermal_gap 0.0508)
		)
		(pad "K7" thru_hole circle
			(at 11.999976 11.999976 180)
			(size 0.906272 0.906272)
			(drill 0.499872)
			(layers "*.Cu" "*.Mask")
			(remove_unused_layers no)
			(net "GND")
			(clearance 0.0508)
			(thermal_gap 0.0508)
		)
		(pad "M2" thru_hole circle
			(at 1.999996 14.59992 180)
			(size 0.906272 0.906272)
			(drill 0.499872)
			(layers "*.Cu" "*.Mask")
			(remove_unused_layers no)
			(net "GND")
			(clearance 0.0508)
			(thermal_gap 0.0508)
		)
		(pad "M4" thru_hole circle
			(at 5.999988 14.59992 180)
			(size 0.906272 0.906272)
			(drill 0.499872)
			(layers "*.Cu" "*.Mask")
			(remove_unused_layers no)
			(net "GND")
			(clearance 0.0508)
			(thermal_gap 0.0508)
		)
		(pad "M6" thru_hole circle
			(at 9.99998 14.59992 180)
			(size 0.906272 0.906272)
			(drill 0.499872)
			(layers "*.Cu" "*.Mask")
			(remove_unused_layers no)
			(net "GND")
			(clearance 0.0508)
			(thermal_gap 0.0508)
		)
		(pad "M8" thru_hole circle
			(at 13.999972 14.59992 180)
			(size 0.906272 0.906272)
			(drill 0.499872)
			(layers "*.Cu" "*.Mask")
			(remove_unused_layers no)
			(net "GND")
			(clearance 0.0508)
			(thermal_gap 0.0508)
		)
		(pad "N1" thru_hole circle
			(at 0 15.599918 180)
			(size 0.906272 0.906272)
			(drill 0.499872)
			(layers "*.Cu" "*.Mask")
			(remove_unused_layers no)
			(net "GND")
			(clearance 0.0508)
			(thermal_gap 0.0508)
		)
		(pad "N2" thru_hole circle
			(at 1.999996 15.80007 180)
			(size 0.766318 0.766318)
			(drill 0.359918)
			(layers "*.Cu" "*.Mask")
			(remove_unused_layers no)
			(net "GPU_FPGA_EROT_FATALERR_N")
			(clearance 0.0508)
			(thermal_gap 0.0508)
		)
		(pad "N3" thru_hole circle
			(at 3.999992 15.599918 180)
			(size 0.906272 0.906272)
			(drill 0.499872)
			(layers "*.Cu" "*.Mask")
			(remove_unused_layers no)
			(net "GND")
			(clearance 0.0508)
			(thermal_gap 0.0508)
		)
		(pad "N4" thru_hole circle
			(at 5.999988 15.80007 180)
			(size 0.766318 0.766318)
			(drill 0.359918)
			(layers "*.Cu" "*.Mask")
			(remove_unused_layers no)
			(net "GPU_3V3IO_RSVD0_FFU")
			(clearance 0.0508)
			(thermal_gap 0.0508)
		)
		(pad "N5" thru_hole circle
			(at 7.999984 15.599918 180)
			(size 0.906272 0.906272)
			(drill 0.499872)
			(layers "*.Cu" "*.Mask")
			(remove_unused_layers no)
			(net "GND")
			(clearance 0.0508)
			(thermal_gap 0.0508)
		)
		(pad "N6" thru_hole circle
			(at 9.99998 15.80007 180)
			(size 0.766318 0.766318)
			(drill 0.359918)
			(layers "*.Cu" "*.Mask")
			(remove_unused_layers no)
			(net "GPU_3V3IO_RSVD1_FFU")
			(clearance 0.0508)
			(thermal_gap 0.0508)
		)
		(pad "N7" thru_hole circle
			(at 11.999976 15.599918 180)
			(size 0.906272 0.906272)
			(drill 0.499872)
			(layers "*.Cu" "*.Mask")
			(remove_unused_layers no)
			(net "GND")
			(clearance 0.0508)
			(thermal_gap 0.0508)
		)
		(pad "N8" thru_hole circle
			(at 13.999972 15.80007 180)
			(size 0.766318 0.766318)
			(drill 0.359918)
			(layers "*.Cu" "*.Mask")
			(remove_unused_layers no)
			(net "PRSNT_CABLE_GPU_B3_N")
			(clearance 0.0508)
			(thermal_gap 0.0508)
		)
	)
)
